(kicad_pcb
	(version 20241229)
	(generator "pcbnew")
	(generator_version "9.0")
	(general
		(thickness 1.294)
		(legacy_teardrops no)
	)
	(paper "A3")
	(title_block
		(title "Kintex 410T devboard")
		(date "2024-04-03")
		(rev "1.1.2")
		(comment 9 "footprints 719-724 of 975")
	)
	(layers
		(0 "F.Cu" mixed)
		(4 "In1.Cu" power)
		(6 "In2.Cu" power)
		(8 "In3.Cu" mixed)
		(10 "In4.Cu" power)
		(12 "In5.Cu" mixed)
		(14 "In6.Cu" power)
		(16 "In7.Cu" mixed)
		(18 "In8.Cu" power)
		(2 "B.Cu" mixed)
		(9 "F.Adhes" user "F.Adhesive")
		(11 "B.Adhes" user "B.Adhesive")
		(13 "F.Paste" user)
		(15 "B.Paste" user)
		(5 "F.SilkS" user "F.Silkscreen")
		(7 "B.SilkS" user "B.Silkscreen")
		(1 "F.Mask" user)
		(3 "B.Mask" user)
		(17 "Dwgs.User" user "User.Drawings")
		(19 "Cmts.User" user "User.Comments")
		(21 "Eco1.User" user "User.Eco1")
		(23 "Eco2.User" user "User.Eco2")
		(25 "Edge.Cuts" user)
		(27 "Margin" user)
		(31 "F.CrtYd" user "F.Courtyard")
		(29 "B.CrtYd" user "B.Courtyard")
		(35 "F.Fab" user)
		(33 "B.Fab" user)
	)
	(footprint "antmicro-footprints:C_0201"
		(layer "B.Cu")
		(at 189.8 117.5 180)
		(descr "Capacitor SMD 0201")
		(tags "capacitor SMD 0201")
		(property "Reference" "C144"
			(at 4.15 0.5 0)
			(layer "B.SilkS")
			(effects
				(font
					(size 0.7 0.7)
					(thickness 0.15)
				)
				(justify left bottom mirror)
			)
		)
		(property "Value" "C_100n_0201"
			(at 0 -1.4 0)
			(layer "B.Fab")
			(effects
				(font
					(size 0.7 0.7)
					(thickness 0.15)
				)
				(justify left bottom mirror)
			)
		)
		(property "Description" "SMD Multilayer Ceramic Capacitor, 0.1 µF, 6.3 V, 0201 [0603 Metric], ± 10%, X6S, CC Series"
			(at 0 0 180)
			(layer "F.Fab")
			(hide yes)
			(effects
				(font
					(size 1.27 1.27)
					(thickness 0.15)
				)
			)
		)
		(property "Author" "Antmicro"
			(at 379.6 235 0)
			(layer "B.Fab")
			(hide yes)
			(effects
				(font
					(size 1 1)
					(thickness 0.15)
				)
				(justify mirror)
			)
		)
		(property "Dielectric" ""
			(at 379.6 235 0)
			(layer "B.Fab")
			(hide yes)
			(effects
				(font
					(size 1 1)
					(thickness 0.15)
				)
				(justify mirror)
			)
		)
		(property "License" "Apache-2.0"
			(at 379.6 235 0)
			(layer "B.Fab")
			(hide yes)
			(effects
				(font
					(size 1 1)
					(thickness 0.15)
				)
				(justify mirror)
			)
		)
		(property "MPN" "CC0201KRX6S5BB104"
			(at 379.6 235 0)
			(layer "B.Fab")
			(hide yes)
			(effects
				(font
					(size 1 1)
					(thickness 0.15)
				)
				(justify mirror)
			)
		)
		(property "Manufacturer" "YAGEO"
			(at 379.6 235 0)
			(layer "B.Fab")
			(hide yes)
			(effects
				(font
					(size 1 1)
					(thickness 0.15)
				)
				(justify mirror)
			)
		)
		(property "Val" "100n"
			(at 379.6 235 0)
			(layer "B.Fab")
			(hide yes)
			(effects
				(font
					(size 1 1)
					(thickness 0.15)
				)
				(justify mirror)
			)
		)
		(property "Voltage" ""
			(at 379.6 235 0)
			(layer "B.Fab")
			(hide yes)
			(effects
				(font
					(size 1 1)
					(thickness 0.15)
				)
				(justify mirror)
			)
		)
		(sheetname "FPGA supply")
		(sheetfile "fpga-supply.kicad_sch")
		(attr smd)
		(fp_rect
			(start -0.7 0.35)
			(end 0.7 -0.35)
			(stroke
				(width 0.05)
				(type default)
			)
			(fill no)
			(layer "B.CrtYd")
		)
		(fp_rect
			(start 0.3 -0.15)
			(end -0.301 0.149)
			(stroke
				(width 0.15)
				(type solid)
			)
			(fill no)
			(layer "B.Fab")
		)
		(pad "" smd roundrect
			(at -0.349 0.002 180)
			(size 0.318 0.36)
			(layers "B.Paste")
			(roundrect_rratio 0.25)
		)
		(pad "" smd roundrect
			(at 0.341 0.002 180)
			(size 0.318 0.36)
			(layers "B.Paste")
			(roundrect_rratio 0.25)
		)
		(pad "1" smd roundrect
			(at -0.321 0.002 180)
			(size 0.46 0.4)
			(layers "B.Cu" "B.Mask")
			(roundrect_rratio 0.25)
			(net 1 "GND")
			(pintype "passive")
		)
		(pad "2" smd roundrect
			(at 0.32 0.002 180)
			(size 0.46 0.4)
			(layers "B.Cu" "B.Mask")
			(roundrect_rratio 0.25)
			(net 8 "+1V2_MGTAVTT")
			(pintype "passive")
		)
	)
	(footprint "antmicro-footprints:R_0402_1005Metric"
		(layer "B.Cu")
		(at 266.8 93.2 -90)
		(descr "Resistor SMD 0402")
		(tags "resistor SMD 0402")
		(property "Reference" "R149"
			(at -1.35 -1.3 90)
			(layer "B.SilkS")
			(effects
				(font
					(size 0.7 0.7)
					(thickness 0.15)
				)
				(justify left bottom mirror)
			)
		)
		(property "Value" "R_10k_0402"
			(at 0 -1.4 90)
			(layer "B.Fab")
			(effects
				(font
					(size 0.7 0.7)
					(thickness 0.15)
				)
				(justify left bottom mirror)
			)
		)
		(property "Description" "SMD Chip Resistor, 10 kohm, ± 1%, 62.5 mW, 0402 [1005 Metric], Thick Film, General Purpose"
			(at 0 0 270)
			(layer "F.Fab")
			(hide yes)
			(effects
				(font
					(size 1.27 1.27)
					(thickness 0.15)
				)
			)
		)
		(property "Author" "Antmicro"
			(at 173.6 360 0)
			(layer "B.Fab")
			(hide yes)
			(effects
				(font
					(size 1 1)
					(thickness 0.15)
				)
				(justify mirror)
			)
		)
		(property "License" "Apache-2.0"
			(at 173.6 360 0)
			(layer "B.Fab")
			(hide yes)
			(effects
				(font
					(size 1 1)
					(thickness 0.15)
				)
				(justify mirror)
			)
		)
		(property "MPN" "CR0402-FX-1002GLF"
			(at 173.6 360 0)
			(layer "B.Fab")
			(hide yes)
			(effects
				(font
					(size 1 1)
					(thickness 0.15)
				)
				(justify mirror)
			)
		)
		(property "Manufacturer" "Bourns"
			(at 173.6 360 0)
			(layer "B.Fab")
			(hide yes)
			(effects
				(font
					(size 1 1)
					(thickness 0.15)
				)
				(justify mirror)
			)
		)
		(property "Tolerance" "1%"
			(at 173.6 360 0)
			(layer "B.Fab")
			(hide yes)
			(effects
				(font
					(size 1 1)
					(thickness 0.15)
				)
				(justify mirror)
			)
		)
		(property "Val" "10k"
			(at 173.6 360 0)
			(layer "B.Fab")
			(hide yes)
			(effects
				(font
					(size 1 1)
					(thickness 0.15)
				)
				(justify mirror)
			)
		)
		(sheetname "User GPIO + LED + button + DIP switch")
		(sheetfile "user-gpio.kicad_sch")
		(attr smd)
		(fp_rect
			(start -0.925 0.47)
			(end 0.925 -0.47)
			(stroke
				(width 0.05)
				(type default)
			)
			(fill no)
			(layer "B.CrtYd")
		)
		(fp_rect
			(start -0.5 0.25)
			(end 0.5 -0.25)
			(stroke
				(width 0.15)
				(type solid)
			)
			(fill no)
			(layer "B.Fab")
		)
		(pad "1" smd roundrect
			(at -0.48 0 270)
			(size 0.59 0.64)
			(layers "B.Cu" "B.Mask" "B.Paste")
			(roundrect_rratio 0.25)
			(net 26 "+1V8")
			(pintype "passive")
		)
		(pad "2" smd roundrect
			(at 0.48 0 270)
			(size 0.59 0.64)
			(layers "B.Cu" "B.Mask" "B.Paste")
			(roundrect_rratio 0.25)
			(net 1232 "/USER_IO.BUTTON3")
			(pintype "passive")
		)
	)
	(footprint "antmicro-footprints:C_0201"
		(layer "B.Cu")
		(at 203.45 128.5 -90)
		(descr "Capacitor SMD 0201")
		(tags "capacitor SMD 0201")
		(property "Reference" "C8"
			(at -29.875 -28.2 90)
			(layer "B.SilkS")
			(effects
				(font
					(size 0.7 0.7)
					(thickness 0.15)
				)
				(justify left bottom mirror)
			)
		)
		(property "Value" "C_4u7_0201"
			(at 0 -1.4 90)
			(layer "B.Fab")
			(effects
				(font
					(size 0.7 0.7)
					(thickness 0.15)
				)
				(justify left bottom mirror)
			)
		)
		(property "Description" "SMD Multilayer Ceramic Capacitor, 4.7 µF, 6.3 V, 0201 [0603 Metric], ± 20%, X5R, GRM Series"
			(at 0 0 270)
			(layer "F.Fab")
			(hide yes)
			(effects
				(font
					(size 1.27 1.27)
					(thickness 0.15)
				)
			)
		)
		(property "Author" "Antmicro"
			(at 74.95 331.95 0)
			(layer "B.Fab")
			(hide yes)
			(effects
				(font
					(size 1 1)
					(thickness 0.15)
				)
				(justify mirror)
			)
		)
		(property "Dielectric" ""
			(at 74.95 331.95 0)
			(layer "B.Fab")
			(hide yes)
			(effects
				(font
					(size 1 1)
					(thickness 0.15)
				)
				(justify mirror)
			)
		)
		(property "License" "Apache-2.0"
			(at 74.95 331.95 0)
			(layer "B.Fab")
			(hide yes)
			(effects
				(font
					(size 1 1)
					(thickness 0.15)
				)
				(justify mirror)
			)
		)
		(property "MPN" "GRM035R60J475ME15D"
			(at 74.95 331.95 0)
			(layer "B.Fab")
			(hide yes)
			(effects
				(font
					(size 1 1)
					(thickness 0.15)
				)
				(justify mirror)
			)
		)
		(property "Manufacturer" "Murata"
			(at 74.95 331.95 0)
			(layer "B.Fab")
			(hide yes)
			(effects
				(font
					(size 1 1)
					(thickness 0.15)
				)
				(justify mirror)
			)
		)
		(property "Val" "4u7"
			(at 74.95 331.95 0)
			(layer "B.Fab")
			(hide yes)
			(effects
				(font
					(size 1 1)
					(thickness 0.15)
				)
				(justify mirror)
			)
		)
		(property "Voltage" ""
			(at 74.95 331.95 0)
			(layer "B.Fab")
			(hide yes)
			(effects
				(font
					(size 1 1)
					(thickness 0.15)
				)
				(justify mirror)
			)
		)
		(sheetname "FPGA supply")
		(sheetfile "fpga-supply.kicad_sch")
		(attr smd)
		(fp_rect
			(start -0.7 0.35)
			(end 0.7 -0.35)
			(stroke
				(width 0.05)
				(type default)
			)
			(fill no)
			(layer "B.CrtYd")
		)
		(fp_rect
			(start 0.3 -0.15)
			(end -0.301 0.149)
			(stroke
				(width 0.15)
				(type solid)
			)
			(fill no)
			(layer "B.Fab")
		)
		(pad "" smd roundrect
			(at -0.349 0.002 270)
			(size 0.318 0.36)
			(layers "B.Paste")
			(roundrect_rratio 0.25)
		)
		(pad "" smd roundrect
			(at 0.341 0.002 270)
			(size 0.318 0.36)
			(layers "B.Paste")
			(roundrect_rratio 0.25)
		)
		(pad "1" smd roundrect
			(at -0.321 0.002 270)
			(size 0.46 0.4)
			(layers "B.Cu" "B.Mask")
			(roundrect_rratio 0.25)
			(net 1 "GND")
			(pintype "passive")
		)
		(pad "2" smd roundrect
			(at 0.32 0.002 270)
			(size 0.46 0.4)
			(layers "B.Cu" "B.Mask")
			(roundrect_rratio 0.25)
			(net 650 "+1V0")
			(pintype "passive")
		)
	)
	(footprint "antmicro-footprints:R_0402_1005Metric"
		(layer "B.Cu")
		(at 179.05 175.2625 90)
		(descr "Resistor SMD 0402")
		(tags "resistor SMD 0402")
		(property "Reference" "R314"
			(at -0.7375 0.425 270)
			(layer "B.SilkS")
			(effects
				(font
					(size 0.7 0.7)
					(thickness 0.15)
				)
				(justify left bottom mirror)
			)
		)
		(property "Value" "R_0R_0402"
			(at 0 -1.4 270)
			(layer "B.Fab")
			(effects
				(font
					(size 0.7 0.7)
					(thickness 0.15)
				)
				(justify left bottom mirror)
			)
		)
		(property "Description" "SMD Chip Resistor, Jumper, 0 ohm, 100 mW, 0402 [1005 Metric], Thick Film, General Purpose"
			(at 0 0 90)
			(layer "F.Fab")
			(hide yes)
			(effects
				(font
					(size 1.27 1.27)
					(thickness 0.15)
				)
			)
		)
		(property "Author" "Antmicro"
			(at 354.3125 -3.7875 0)
			(layer "B.Fab")
			(hide yes)
			(effects
				(font
					(size 1 1)
					(thickness 0.15)
				)
				(justify mirror)
			)
		)
		(property "Current" "1A"
			(at 354.3125 -3.7875 0)
			(layer "B.Fab")
			(hide yes)
			(effects
				(font
					(size 1 1)
					(thickness 0.15)
				)
				(justify mirror)
			)
		)
		(property "DNP" "DNP"
			(at 354.3125 -3.7875 0)
			(layer "B.Fab")
			(hide yes)
			(effects
				(font
					(size 1 1)
					(thickness 0.15)
				)
				(justify mirror)
			)
		)
		(property "License" "Apache-2.0"
			(at 354.3125 -3.7875 0)
			(layer "B.Fab")
			(hide yes)
			(effects
				(font
					(size 1 1)
					(thickness 0.15)
				)
				(justify mirror)
			)
		)
		(property "MPN" "ERJ2GE0R00X"
			(at 354.3125 -3.7875 0)
			(layer "B.Fab")
			(hide yes)
			(effects
				(font
					(size 1 1)
					(thickness 0.15)
				)
				(justify mirror)
			)
		)
		(property "Manufacturer" "Panasonic"
			(at 354.3125 -3.7875 0)
			(layer "B.Fab")
			(hide yes)
			(effects
				(font
					(size 1 1)
					(thickness 0.15)
				)
				(justify mirror)
			)
		)
		(property "Tolerance" ""
			(at 354.3125 -3.7875 0)
			(layer "B.Fab")
			(hide yes)
			(effects
				(font
					(size 1 1)
					(thickness 0.15)
				)
				(justify mirror)
			)
		)
		(property "Val" "0R"
			(at 354.3125 -3.7875 0)
			(layer "B.Fab")
			(hide yes)
			(effects
				(font
					(size 1 1)
					(thickness 0.15)
				)
				(justify mirror)
			)
		)
		(property "dnp" ""
			(at 354.3125 -3.7875 0)
			(layer "B.Fab")
			(hide yes)
			(effects
				(font
					(size 1 1)
					(thickness 0.15)
				)
				(justify mirror)
			)
		)
		(property "exclude_from_bom" ""
			(at 354.3125 -3.7875 0)
			(layer "B.Fab")
			(hide yes)
			(effects
				(font
					(size 1 1)
					(thickness 0.15)
				)
				(justify mirror)
			)
		)
		(sheetname "DC-DC Converters")
		(sheetfile "dc-dc.kicad_sch")
		(attr smd exclude_from_bom)
		(fp_rect
			(start -0.925 0.47)
			(end 0.925 -0.47)
			(stroke
				(width 0.05)
				(type default)
			)
			(fill no)
			(layer "B.CrtYd")
		)
		(fp_rect
			(start -0.5 0.25)
			(end 0.5 -0.25)
			(stroke
				(width 0.15)
				(type solid)
			)
			(fill no)
			(layer "B.Fab")
		)
		(pad "1" smd roundrect
			(at -0.48 0 90)
			(size 0.59 0.64)
			(layers "B.Cu" "B.Mask" "B.Paste")
			(roundrect_rratio 0.25)
			(net 1213 "/DC-DC Converters/SENSE_5V_N")
			(pintype "passive")
		)
		(pad "2" smd roundrect
			(at 0.48 0 90)
			(size 0.59 0.64)
			(layers "B.Cu" "B.Mask" "B.Paste")
			(roundrect_rratio 0.25)
			(net 964 "/DC-DC Converters/FB7")
			(pintype "passive")
		)
	)
	(footprint "antmicro-footprints:C_0402_1005Metric"
		(layer "B.Cu")
		(at 189 144.5)
		(descr "Capacitor SMD 0402")
		(tags "capacitor SMD 0402")
		(property "Reference" "C102"
			(at 1.325 1.2 180)
			(layer "B.SilkS")
			(effects
				(font
					(size 0.7 0.7)
					(thickness 0.15)
				)
				(justify left bottom mirror)
			)
		)
		(property "Value" "C_100n_0402"
			(at 0 -1.169 180)
			(layer "B.Fab")
			(effects
				(font
					(size 0.7 0.7)
					(thickness 0.15)
				)
				(justify left bottom mirror)
			)
		)
		(property "Description" "SMD Multilayer Ceramic Capacitor, 0.1 µF, 50 V, 0402 [1005 Metric], ± 10%, X5R, GRM Series"
			(at 0 0 0)
			(layer "F.Fab")
			(hide yes)
			(effects
				(font
					(size 1.27 1.27)
					(thickness 0.15)
				)
			)
		)
		(property "Author" "Antmicro"
			(at 0 0 0)
			(layer "B.Fab")
			(hide yes)
			(effects
				(font
					(size 1 1)
					(thickness 0.15)
				)
				(justify mirror)
			)
		)
		(property "Dielectric" "X5R"
			(at 0 0 0)
			(layer "B.Fab")
			(hide yes)
			(effects
				(font
					(size 1 1)
					(thickness 0.15)
				)
				(justify mirror)
			)
		)
		(property "License" "Apache-2.0"
			(at 0 0 0)
			(layer "B.Fab")
			(hide yes)
			(effects
				(font
					(size 1 1)
					(thickness 0.15)
				)
				(justify mirror)
			)
		)
		(property "MPN" "GRM155R61H104KE14D"
			(at 0 0 0)
			(layer "B.Fab")
			(hide yes)
			(effects
				(font
					(size 1 1)
					(thickness 0.15)
				)
				(justify mirror)
			)
		)
		(property "Manufacturer" "Murata"
			(at 0 0 0)
			(layer "B.Fab")
			(hide yes)
			(effects
				(font
					(size 1 1)
					(thickness 0.15)
				)
				(justify mirror)
			)
		)
		(property "Val" "100n"
			(at 0 0 0)
			(layer "B.Fab")
			(hide yes)
			(effects
				(font
					(size 1 1)
					(thickness 0.15)
				)
				(justify mirror)
			)
		)
		(property "Voltage" "50V"
			(at 0 0 0)
			(layer "B.Fab")
			(hide yes)
			(effects
				(font
					(size 1 1)
					(thickness 0.15)
				)
				(justify mirror)
			)
		)
		(sheetname "FPGA Bank 33 & 34")
		(sheetfile "fpga-bank-33-34.kicad_sch")
		(attr smd)
		(fp_rect
			(start -0.925 0.47)
			(end 0.925 -0.47)
			(stroke
				(width 0.05)
				(type default)
			)
			(fill no)
			(layer "B.CrtYd")
		)
		(fp_line
			(start -0.494 -0.248)
			(end -0.494 0.25)
			(stroke
				(width 0.15)
				(type solid)
			)
			(layer "B.Fab")
		)
		(fp_line
			(start -0.494 0.25)
			(end 0.504 0.25)
			(stroke
				(width 0.15)
				(type solid)
			)
			(layer "B.Fab")
		)
		(fp_line
			(start 0.504 -0.248)
			(end -0.494 -0.248)
			(stroke
				(width 0.15)
				(type solid)
			)
			(layer "B.Fab")
		)
		(fp_line
			(start 0.504 0.25)
			(end 0.504 -0.248)
			(stroke
				(width 0.15)
				(type solid)
			)
			(layer "B.Fab")
		)
		(pad "1" smd roundrect
			(at -0.48 0)
			(size 0.59 0.64)
			(layers "B.Cu" "B.Mask" "B.Paste")
			(roundrect_rratio 0.25)
			(net 1 "GND")
			(pintype "passive")
		)
		(pad "2" smd roundrect
			(at 0.48 0)
			(size 0.59 0.64)
			(layers "B.Cu" "B.Mask" "B.Paste")
			(roundrect_rratio 0.25)
			(net 25 "+1V35")
			(pintype "passive")
		)
	)
	(footprint "antmicro-footprints:C_0402_1005Metric"
		(layer "B.Cu")
		(at 160.5 146.475 -90)
		(descr "Capacitor SMD 0402")
		(tags "capacitor SMD 0402")
		(property "Reference" "C168"
			(at -1.025 3.475 90)
			(layer "B.SilkS")
			(effects
				(font
					(size 0.7 0.7)
					(thickness 0.15)
				)
				(justify left bottom mirror)
			)
		)
		(property "Value" "C_10u_0402"
			(at 0 -1.4 90)
			(layer "B.Fab")
			(effects
				(font
					(size 0.7 0.7)
					(thickness 0.15)
				)
				(justify left bottom mirror)
			)
		)
		(property "Description" "SMD Multilayer Ceramic Capacitor, 10 µF, 6.3 V, 0402 [1005 Metric], ± 20%, X5R, CC Series"
			(at 0 0 270)
			(layer "F.Fab")
			(hide yes)
			(effects
				(font
					(size 1.27 1.27)
					(thickness 0.15)
				)
			)
		)
		(property "Author" "Antmicro"
			(at 14.025 306.975 0)
			(layer "B.Fab")
			(hide yes)
			(effects
				(font
					(size 1 1)
					(thickness 0.15)
				)
				(justify mirror)
			)
		)
		(property "Dielectric" ""
			(at 14.025 306.975 0)
			(layer "B.Fab")
			(hide yes)
			(effects
				(font
					(size 1 1)
					(thickness 0.15)
				)
				(justify mirror)
			)
		)
		(property "License" "Apache-2.0"
			(at 14.025 306.975 0)
			(layer "B.Fab")
			(hide yes)
			(effects
				(font
					(size 1 1)
					(thickness 0.15)
				)
				(justify mirror)
			)
		)
		(property "MPN" "CC0402MRX5R5BB106"
			(at 14.025 306.975 0)
			(layer "B.Fab")
			(hide yes)
			(effects
				(font
					(size 1 1)
					(thickness 0.15)
				)
				(justify mirror)
			)
		)
		(property "Manufacturer" "YAGEO"
			(at 14.025 306.975 0)
			(layer "B.Fab")
			(hide yes)
			(effects
				(font
					(size 1 1)
					(thickness 0.15)
				)
				(justify mirror)
			)
		)
		(property "Val" "10u"
			(at 14.025 306.975 0)
			(layer "B.Fab")
			(hide yes)
			(effects
				(font
					(size 1 1)
					(thickness 0.15)
				)
				(justify mirror)
			)
		)
		(property "Voltage" ""
			(at 14.025 306.975 0)
			(layer "B.Fab")
			(hide yes)
			(effects
				(font
					(size 1 1)
					(thickness 0.15)
				)
				(justify mirror)
			)
		)
		(sheetname "DRAM + SRAM")
		(sheetfile "ram.kicad_sch")
		(attr smd)
		(fp_rect
			(start -0.925 0.47)
			(end 0.925 -0.47)
			(stroke
				(width 0.05)
				(type default)
			)
			(fill no)
			(layer "B.CrtYd")
		)
		(fp_line
			(start -0.494 0.25)
			(end 0.504 0.25)
			(stroke
				(width 0.15)
				(type solid)
			)
			(layer "B.Fab")
		)
		(fp_line
			(start 0.504 0.25)
			(end 0.504 -0.248)
			(stroke
				(width 0.15)
				(type solid)
			)
			(layer "B.Fab")
		)
		(fp_line
			(start -0.494 -0.248)
			(end -0.494 0.25)
			(stroke
				(width 0.15)
				(type solid)
			)
			(layer "B.Fab")
		)
		(fp_line
			(start 0.504 -0.248)
			(end -0.494 -0.248)
			(stroke
				(width 0.15)
				(type solid)
			)
			(layer "B.Fab")
		)
		(pad "1" smd roundrect
			(at -0.48 0 270)
			(size 0.59 0.64)
			(layers "B.Cu" "B.Mask" "B.Paste")
			(roundrect_rratio 0.25)
			(net 7 "+0V675_VTT")
			(pintype "passive")
		)
		(pad "2" smd roundrect
			(at 0.48 0 270)
			(size 0.59 0.64)
			(layers "B.Cu" "B.Mask" "B.Paste")
			(roundrect_rratio 0.25)
			(net 25 "+1V35")
			(pintype "passive")
		)
	)
)
